(kicad_pcb
	(version 20241229)
	(generator "pcbnew")
	(generator_version "9.0")
	(general
		(thickness 1.711)
		(legacy_teardrops no)
	)
	(paper "A4")
	(title_block
		(title "Antmicro Baseboard for Jetson AGX Thor")
		(date "2026-02-18")
		(rev "1.1.0")
		(company "Antmicro Ltd")
		(comment 1 "www.antmicro.com")
		(comment 9 "footprints 1010-1015 of 1170")
	)
	(layers
		(0 "F.Cu" signal)
		(4 "In1.Cu" signal)
		(6 "In2.Cu" signal)
		(8 "In3.Cu" signal)
		(10 "In4.Cu" jumper)
		(12 "In5.Cu" signal)
		(14 "In6.Cu" signal)
		(16 "In7.Cu" signal)
		(18 "In8.Cu" signal)
		(2 "B.Cu" signal)
		(9 "F.Adhes" user "F.Adhesive")
		(11 "B.Adhes" user "B.Adhesive")
		(13 "F.Paste" user)
		(15 "B.Paste" user)
		(5 "F.SilkS" user "F.Silkscreen")
		(7 "B.SilkS" user "B.Silkscreen")
		(1 "F.Mask" user)
		(3 "B.Mask" user)
		(17 "Dwgs.User" user "User.Drawings")
		(19 "Cmts.User" user "User.Comments")
		(21 "Eco1.User" user "User.Eco1")
		(23 "Eco2.User" user "User.Eco2")
		(25 "Edge.Cuts" user)
		(27 "Margin" user)
		(31 "F.CrtYd" user "F.Courtyard")
		(29 "B.CrtYd" user "B.Courtyard")
		(35 "F.Fab" user)
		(33 "B.Fab" user)
	)
	(footprint "antmicro-footprints:R_0402_1005Metric"
		(layer "B.Cu")
		(at 96 62.99 90)
		(descr "Resistor SMD 0402")
		(tags "resistor SMD 0402")
		(property "Reference" "R47"
			(at -1.26 -2.5 90)
			(layer "B.SilkS")
			(effects
				(font
					(size 0.7 0.7)
					(thickness 0.15)
				)
				(justify right top mirror)
			)
		)
		(property "Value" "R_100k_0402"
			(at -1.011843 -1.772047 90)
			(layer "B.Fab")
			(effects
				(font
					(size 0.7 0.7)
					(thickness 0.15)
				)
				(justify right top mirror)
			)
		)
		(property "Datasheet" "https://www.bourns.com/docs/product-datasheets/cr.pdf"
			(at 0 0 90)
			(layer "B.Fab")
			(hide yes)
			(effects
				(font
					(size 1.27 1.27)
					(thickness 0.15)
				)
				(justify mirror)
			)
		)
		(property "Description" "SMD Chip Resistor, 100 kohm, ± 1%, 62.5 mW, 0402 [1005 Metric], Thick Film, General Purpose"
			(at 0 0 90)
			(layer "B.Fab")
			(hide yes)
			(effects
				(font
					(size 1.27 1.27)
					(thickness 0.15)
				)
				(justify mirror)
			)
		)
		(property "MPN" "CR0402-FX-1003GLF"
			(at 0 0 270)
			(unlocked yes)
			(layer "B.Fab")
			(hide yes)
			(effects
				(font
					(size 1 1)
					(thickness 0.15)
				)
				(justify mirror)
			)
		)
		(property "Manufacturer" "Bourns"
			(at 0 0 270)
			(unlocked yes)
			(layer "B.Fab")
			(hide yes)
			(effects
				(font
					(size 1 1)
					(thickness 0.15)
				)
				(justify mirror)
			)
		)
		(property "License" "Apache-2.0"
			(at 0 0 270)
			(unlocked yes)
			(layer "B.Fab")
			(hide yes)
			(effects
				(font
					(size 1 1)
					(thickness 0.15)
				)
				(justify mirror)
			)
		)
		(property "Author" "Antmicro"
			(at 0 0 270)
			(unlocked yes)
			(layer "B.Fab")
			(hide yes)
			(effects
				(font
					(size 1 1)
					(thickness 0.15)
				)
				(justify mirror)
			)
		)
		(property "Val" "100k"
			(at 0 0 270)
			(unlocked yes)
			(layer "B.Fab")
			(hide yes)
			(effects
				(font
					(size 1 1)
					(thickness 0.15)
				)
				(justify mirror)
			)
		)
		(property "Tolerance" "1%"
			(at 0 0 270)
			(unlocked yes)
			(layer "B.Fab")
			(hide yes)
			(effects
				(font
					(size 1 1)
					(thickness 0.15)
				)
				(justify mirror)
			)
		)
		(sheetname "/SoM_Power/")
		(sheetfile "som_power.kicad_sch")
		(attr smd)
		(fp_rect
			(start -0.925 0.47)
			(end 0.925 -0.47)
			(stroke
				(width 0.05)
				(type default)
			)
			(fill no)
			(layer "B.CrtYd")
		)
		(fp_rect
			(start -0.5 0.25)
			(end 0.5 -0.25)
			(stroke
				(width 0.15)
				(type solid)
			)
			(fill no)
			(layer "B.Fab")
		)
		(fp_text user "Author: Antmicro"
			(at -0.95 -4.169 90)
			(layer "B.Fab")
			(effects
				(font
					(size 0.7 0.7)
					(thickness 0.15)
				)
				(justify right top mirror)
			)
		)
		(fp_text user "${REFERENCE}"
			(at -0.95 -3.168 90)
			(layer "B.Fab")
			(effects
				(font
					(size 0.7 0.7)
					(thickness 0.15)
				)
				(justify right top mirror)
			)
		)
		(fp_text user "License: Apache-2.0"
			(at -0.95 -5.169 90)
			(layer "B.Fab")
			(effects
				(font
					(size 0.7 0.7)
					(thickness 0.15)
				)
				(justify right top mirror)
			)
		)
		(pad "1" smd roundrect
			(at -0.48 0 90)
			(size 0.59 0.64)
			(layers "B.Cu" "B.Mask" "B.Paste")
			(roundrect_rratio 0.25)
			(net 1298 "Net-(Q37-G)")
			(pintype "passive")
		)
		(pad "2" smd roundrect
			(at 0.48 0 90)
			(size 0.59 0.64)
			(layers "B.Cu" "B.Mask" "B.Paste")
			(roundrect_rratio 0.25)
			(net 4 "+3V3_AON")
			(pintype "passive")
		)
	)
	(footprint "antmicro-footprints:R_0402_1005Metric"
		(layer "B.Cu")
		(at 103.92 64.5 -90)
		(descr "Resistor SMD 0402")
		(tags "resistor SMD 0402")
		(property "Reference" "R3"
			(at -2.5 -0.48 90)
			(layer "B.SilkS")
			(effects
				(font
					(size 0.7 0.7)
					(thickness 0.15)
				)
				(justify left bottom mirror)
			)
		)
		(property "Value" "R_33R_0402"
			(at -1.011843 -1.772047 90)
			(layer "B.Fab")
			(effects
				(font
					(size 0.7 0.7)
					(thickness 0.15)
				)
				(justify left bottom mirror)
			)
		)
		(property "Datasheet" "https://www.bourns.com/docs/product-datasheets/cr.pdf"
			(at 0 0 90)
			(layer "B.Fab")
			(hide yes)
			(effects
				(font
					(size 1.27 1.27)
					(thickness 0.15)
				)
				(justify mirror)
			)
		)
		(property "Description" "SMD Chip Resistor, 33 ohm, ± 1%, 62.5 mW, 0402 [1005 Metric], Thick Film, General Purpose"
			(at 0 0 90)
			(layer "B.Fab")
			(hide yes)
			(effects
				(font
					(size 1.27 1.27)
					(thickness 0.15)
				)
				(justify mirror)
			)
		)
		(property "MPN" "CR0402-FX-33R0GLF"
			(at 0 0 90)
			(unlocked yes)
			(layer "B.Fab")
			(hide yes)
			(effects
				(font
					(size 1 1)
					(thickness 0.15)
				)
				(justify mirror)
			)
		)
		(property "Manufacturer" "Bourns"
			(at 0 0 90)
			(unlocked yes)
			(layer "B.Fab")
			(hide yes)
			(effects
				(font
					(size 1 1)
					(thickness 0.15)
				)
				(justify mirror)
			)
		)
		(property "License" "Apache-2.0"
			(at 0 0 90)
			(unlocked yes)
			(layer "B.Fab")
			(hide yes)
			(effects
				(font
					(size 1 1)
					(thickness 0.15)
				)
				(justify mirror)
			)
		)
		(property "Author" "Antmicro"
			(at 0 0 90)
			(unlocked yes)
			(layer "B.Fab")
			(hide yes)
			(effects
				(font
					(size 1 1)
					(thickness 0.15)
				)
				(justify mirror)
			)
		)
		(property "Val" "33R"
			(at 0 0 90)
			(unlocked yes)
			(layer "B.Fab")
			(hide yes)
			(effects
				(font
					(size 1 1)
					(thickness 0.15)
				)
				(justify mirror)
			)
		)
		(property "Tolerance" "1%"
			(at 0 0 90)
			(unlocked yes)
			(layer "B.Fab")
			(hide yes)
			(effects
				(font
					(size 1 1)
					(thickness 0.15)
				)
				(justify mirror)
			)
		)
		(sheetname "/SoM_IO2/")
		(sheetfile "som_io2.kicad_sch")
		(attr smd)
		(fp_rect
			(start -0.925 0.47)
			(end 0.925 -0.47)
			(stroke
				(width 0.05)
				(type default)
			)
			(fill no)
			(layer "B.CrtYd")
		)
		(fp_rect
			(start -0.5 0.25)
			(end 0.5 -0.25)
			(stroke
				(width 0.15)
				(type solid)
			)
			(fill no)
			(layer "B.Fab")
		)
		(fp_text user "Author: Antmicro"
			(at -0.95 -4.169 90)
			(layer "B.Fab")
			(effects
				(font
					(size 0.7 0.7)
					(thickness 0.15)
				)
				(justify left bottom mirror)
			)
		)
		(fp_text user "${REFERENCE}"
			(at -0.95 -3.168 90)
			(layer "B.Fab")
			(effects
				(font
					(size 0.7 0.7)
					(thickness 0.15)
				)
				(justify left bottom mirror)
			)
		)
		(fp_text user "License: Apache-2.0"
			(at -0.95 -5.169 90)
			(layer "B.Fab")
			(effects
				(font
					(size 0.7 0.7)
					(thickness 0.15)
				)
				(justify left bottom mirror)
			)
		)
		(pad "1" smd roundrect
			(at -0.48 0 270)
			(size 0.59 0.64)
			(layers "B.Cu" "B.Mask" "B.Paste")
			(roundrect_rratio 0.25)
			(net 895 "/SoM_IO2/SFI_CLK-")
			(pintype "passive")
		)
		(pad "2" smd roundrect
			(at 0.48 0 270)
			(size 0.59 0.64)
			(layers "B.Cu" "B.Mask" "B.Paste")
			(roundrect_rratio 0.25)
			(net 171 "/SoM_IO2/SFI_REFCLK-")
			(pintype "passive")
		)
	)
	(footprint "antmicro-footprints:Fiducial_1mm_Mask3mm"
		(layer "B.Cu")
		(at 63.11 150.58 180)
		(descr "Circular Fiducial, 1.5mm bare copper, 3mm soldermask opening")
		(tags "fiducial")
		(property "Reference" "FD7"
			(at -0.93 1.67 0)
			(layer "B.SilkS")
			(effects
				(font
					(size 0.7 0.7)
					(thickness 0.15)
				)
				(justify left bottom mirror)
			)
		)
		(property "Value" "Fiducial_1mm_Mask3mm"
			(at 0 -2.603 0)
			(layer "B.Fab")
			(effects
				(font
					(size 0.7 0.7)
					(thickness 0.15)
				)
				(justify left bottom mirror)
			)
		)
		(property "Description" "Fiducial mask"
			(at 0 0 0)
			(layer "B.Fab")
			(hide yes)
			(effects
				(font
					(size 1.27 1.27)
					(thickness 0.15)
				)
				(justify mirror)
			)
		)
		(property "Author" "Antmicro"
			(at 0 0 0)
			(unlocked yes)
			(layer "B.Fab")
			(hide yes)
			(effects
				(font
					(size 1 1)
					(thickness 0.15)
				)
				(justify mirror)
			)
		)
		(property "License" "Apache-2.0"
			(at 0 0 0)
			(unlocked yes)
			(layer "B.Fab")
			(hide yes)
			(effects
				(font
					(size 1 1)
					(thickness 0.15)
				)
				(justify mirror)
			)
		)
		(sheetname "/")
		(sheetfile "jetson-agx-thor-baseboard.kicad_sch")
		(attr exclude_from_pos_files exclude_from_bom)
		(fp_circle
			(center 0 0)
			(end 1.5 0)
			(stroke
				(width 0.05)
				(type solid)
			)
			(fill no)
			(layer "B.CrtYd")
		)
		(fp_circle
			(center 0 0)
			(end 1.5 0)
			(stroke
				(width 0.15)
				(type solid)
			)
			(fill no)
			(layer "B.Fab")
		)
		(fp_text user "License: Apache-2.0"
			(at -1.25 -7.003 0)
			(layer "B.Fab")
			(effects
				(font
					(size 0.7 0.7)
					(thickness 0.15)
				)
				(justify left bottom mirror)
			)
		)
		(fp_text user "Author: Antmicro"
			(at -1.25 -5.803 0)
			(layer "B.Fab")
			(effects
				(font
					(size 0.7 0.7)
					(thickness 0.15)
				)
				(justify left bottom mirror)
			)
		)
		(fp_text user "${REFERENCE}"
			(at -1.25 -4.603 0)
			(layer "B.Fab")
			(effects
				(font
					(size 0.7 0.7)
					(thickness 0.15)
				)
				(justify left bottom mirror)
			)
		)
		(pad "" smd circle
			(at 0 0 180)
			(size 1 1)
			(layers "B.Cu" "B.Mask")
			(solder_mask_margin 1)
			(clearance 1)
		)
	)
	(footprint "antmicro-footprints:C_0402_1005Metric"
		(layer "B.Cu")
		(at 161.5 64.49)
		(descr "Capacitor SMD 0402")
		(tags "capacitor SMD 0402")
		(property "Reference" "C237"
			(at -3.8 -0.29 0)
			(layer "B.SilkS")
			(effects
				(font
					(size 0.7 0.7)
					(thickness 0.15)
				)
				(justify right top mirror)
			)
		)
		(property "Value" "C_100n_0402"
			(at -1.022927 -2.155213 0)
			(layer "B.Fab")
			(effects
				(font
					(size 0.7 0.7)
					(thickness 0.15)
				)
				(justify right top mirror)
			)
		)
		(property "Datasheet" "https://www.murata.com/products/productdetail?partno=GRM155R61H104KE14%23"
			(at 0 0 0)
			(layer "B.Fab")
			(hide yes)
			(effects
				(font
					(size 1.27 1.27)
					(thickness 0.15)
				)
				(justify mirror)
			)
		)
		(property "Description" "SMD Multilayer Ceramic Capacitor, 0.1 µF, 50 V, 0402 [1005 Metric], ± 10%, X5R, GRM Series"
			(at 0 0 0)
			(layer "B.Fab")
			(hide yes)
			(effects
				(font
					(size 1.27 1.27)
					(thickness 0.15)
				)
				(justify mirror)
			)
		)
		(property "MPN" "GRM155R61H104KE14D"
			(at 0 0 180)
			(unlocked yes)
			(layer "B.Fab")
			(hide yes)
			(effects
				(font
					(size 1 1)
					(thickness 0.15)
				)
				(justify mirror)
			)
		)
		(property "Val" "100n"
			(at 0 0 180)
			(unlocked yes)
			(layer "B.Fab")
			(hide yes)
			(effects
				(font
					(size 1 1)
					(thickness 0.15)
				)
				(justify mirror)
			)
		)
		(property "Voltage" "50V"
			(at 0 0 180)
			(unlocked yes)
			(layer "B.Fab")
			(hide yes)
			(effects
				(font
					(size 1 1)
					(thickness 0.15)
				)
				(justify mirror)
			)
		)
		(property "Dielectric" "X5R"
			(at 0 0 180)
			(unlocked yes)
			(layer "B.Fab")
			(hide yes)
			(effects
				(font
					(size 1 1)
					(thickness 0.15)
				)
				(justify mirror)
			)
		)
		(property "Manufacturer" "Murata"
			(at 0 0 180)
			(unlocked yes)
			(layer "B.Fab")
			(hide yes)
			(effects
				(font
					(size 1 1)
					(thickness 0.15)
				)
				(justify mirror)
			)
		)
		(property "License" "Apache-2.0"
			(at 0 0 180)
			(unlocked yes)
			(layer "B.Fab")
			(hide yes)
			(effects
				(font
					(size 1 1)
					(thickness 0.15)
				)
				(justify mirror)
			)
		)
		(property "Author" "Antmicro"
			(at 0 0 180)
			(unlocked yes)
			(layer "B.Fab")
			(hide yes)
			(effects
				(font
					(size 1 1)
					(thickness 0.15)
				)
				(justify mirror)
			)
		)
		(sheetname "/SoM_IO2/")
		(sheetfile "som_io2.kicad_sch")
		(attr smd exclude_from_pos_files exclude_from_bom dnp)
		(fp_rect
			(start -0.925 0.47)
			(end 0.925 -0.47)
			(stroke
				(width 0.05)
				(type default)
			)
			(fill no)
			(layer "B.CrtYd")
		)
		(fp_line
			(start -0.494 -0.248)
			(end -0.494 0.25)
			(stroke
				(width 0.15)
				(type solid)
			)
			(layer "B.Fab")
		)
		(fp_line
			(start -0.494 0.25)
			(end 0.504 0.25)
			(stroke
				(width 0.15)
				(type solid)
			)
			(layer "B.Fab")
		)
		(fp_line
			(start 0.504 -0.248)
			(end -0.494 -0.248)
			(stroke
				(width 0.15)
				(type solid)
			)
			(layer "B.Fab")
		)
		(fp_line
			(start 0.504 0.25)
			(end 0.504 -0.248)
			(stroke
				(width 0.15)
				(type solid)
			)
			(layer "B.Fab")
		)
		(fp_text user "${REFERENCE}"
			(at -0.939 -4.599 0)
			(layer "B.Fab")
			(effects
				(font
					(size 0.7 0.7)
					(thickness 0.15)
				)
				(justify right top mirror)
			)
		)
		(fp_text user "Author: Antmicro"
			(at -0.939 -3.399 0)
			(layer "B.Fab")
			(effects
				(font
					(size 0.7 0.7)
					(thickness 0.15)
				)
				(justify right top mirror)
			)
		)
		(fp_text user "License: Apache-2.0"
			(at -0.939 -5.799 0)
			(layer "B.Fab")
			(effects
				(font
					(size 0.7 0.7)
					(thickness 0.15)
				)
				(justify right top mirror)
			)
		)
		(pad "1" smd roundrect
			(at -0.48 0)
			(size 0.59 0.64)
			(layers "B.Cu" "B.Mask" "B.Paste")
			(roundrect_rratio 0.25)
			(net 1 "GND")
			(pintype "passive")
		)
		(pad "2" smd roundrect
			(at 0.48 0)
			(size 0.59 0.64)
			(layers "B.Cu" "B.Mask" "B.Paste")
			(roundrect_rratio 0.25)
			(net 269 "/SoM_IO2/TC_VCC")
			(pintype "passive")
		)
	)
	(footprint "antmicro-footprints:TP_SMD_0.75mm"
		(layer "B.Cu")
		(at 92.6 69.3 -90)
		(property "Reference" "TP81"
			(at 0 0.6 90)
			(layer "B.SilkS")
			(effects
				(font
					(size 0.7 0.7)
					(thickness 0.15)
				)
				(justify left bottom mirror)
			)
		)
		(property "Value" "TP_0.75mm_SMD"
			(at 0 -1.2 90)
			(layer "B.Fab")
			(effects
				(font
					(size 0.7 0.7)
					(thickness 0.15)
				)
				(justify left bottom mirror)
			)
		)
		(property "Description" "SMT test point"
			(at 0 0 90)
			(layer "B.Fab")
			(hide yes)
			(effects
				(font
					(size 1.27 1.27)
					(thickness 0.15)
				)
				(justify mirror)
			)
		)
		(property "MPN" ""
			(at 0 0 90)
			(unlocked yes)
			(layer "B.Fab")
			(hide yes)
			(effects
				(font
					(size 1 1)
					(thickness 0.15)
				)
				(justify mirror)
			)
		)
		(property "Manufacturer" ""
			(at 0 0 90)
			(unlocked yes)
			(layer "B.Fab")
			(hide yes)
			(effects
				(font
					(size 1 1)
					(thickness 0.15)
				)
				(justify mirror)
			)
		)
		(property "Author" "Antmicro"
			(at 0 0 90)
			(unlocked yes)
			(layer "B.Fab")
			(hide yes)
			(effects
				(font
					(size 1 1)
					(thickness 0.15)
				)
				(justify mirror)
			)
		)
		(property "License" "Apache-2.0"
			(at 0 0 90)
			(unlocked yes)
			(layer "B.Fab")
			(hide yes)
			(effects
				(font
					(size 1 1)
					(thickness 0.15)
				)
				(justify mirror)
			)
		)
		(sheetname "/SoM_Power/")
		(sheetfile "som_power.kicad_sch")
		(attr exclude_from_pos_files exclude_from_bom)
		(fp_circle
			(center 0 0)
			(end 0.475 0)
			(stroke
				(width 0.05)
				(type default)
			)
			(fill no)
			(layer "B.CrtYd")
		)
		(fp_text user "Author: Antmicro"
			(at -0.4 -3.901 90)
			(layer "B.Fab")
			(effects
				(font
					(size 0.7 0.7)
					(thickness 0.15)
				)
				(justify left bottom mirror)
			)
		)
		(fp_text user "${REFERENCE}"
			(at -0.4 -2.7 90)
			(layer "B.Fab")
			(effects
				(font
					(size 0.7 0.7)
					(thickness 0.15)
				)
				(justify left bottom mirror)
			)
		)
		(fp_text user "License: Apache-2.0"
			(at -0.4 -5.101 90)
			(layer "B.Fab")
			(effects
				(font
					(size 0.7 0.7)
					(thickness 0.15)
				)
				(justify left bottom mirror)
			)
		)
		(pad "1" smd circle
			(at 0 0 270)
			(size 0.75 0.75)
			(layers "B.Cu" "B.Mask")
			(net 495 "/SoM_Power/~{FORCE_RECOVERY}")
			(pinfunction "1")
			(pintype "passive")
		)
	)
	(footprint "antmicro-footprints:R_0402_1005Metric"
		(layer "B.Cu")
		(at 224.046 77.865)
		(descr "Resistor SMD 0402")
		(tags "resistor SMD 0402")
		(property "Reference" "R147"
			(at -1.746 -2.265 0)
			(layer "B.SilkS")
			(effects
				(font
					(size 0.7 0.7)
					(thickness 0.15)
				)
				(justify right top mirror)
			)
		)
		(property "Value" "R_27R_0402"
			(at -1.011843 -1.772047 0)
			(layer "B.Fab")
			(effects
				(font
					(size 0.7 0.7)
					(thickness 0.15)
				)
				(justify right top mirror)
			)
		)
		(property "Datasheet" "https://www.bourns.com/docs/product-datasheets/cr.pdf"
			(at 0 0 0)
			(layer "B.Fab")
			(hide yes)
			(effects
				(font
					(size 1.27 1.27)
					(thickness 0.15)
				)
				(justify mirror)
			)
		)
		(property "Description" "SMD Chip Resistor, 27 ohm, ± 1%, 63 mW, 0402 [1005 Metric], Thick Film, General Purpose"
			(at 0 0 0)
			(layer "B.Fab")
			(hide yes)
			(effects
				(font
					(size 1.27 1.27)
					(thickness 0.15)
				)
				(justify mirror)
			)
		)
		(property "Manufacturer" "Bourns"
			(at 0 0 180)
			(unlocked yes)
			(layer "B.Fab")
			(hide yes)
			(effects
				(font
					(size 1 1)
					(thickness 0.15)
				)
				(justify mirror)
			)
		)
		(property "MPN" "CR0402-FX-27R0GLF"
			(at 0 0 180)
			(unlocked yes)
			(layer "B.Fab")
			(hide yes)
			(effects
				(font
					(size 1 1)
					(thickness 0.15)
				)
				(justify mirror)
			)
		)
		(property "Val" "27R"
			(at 0 0 180)
			(unlocked yes)
			(layer "B.Fab")
			(hide yes)
			(effects
				(font
					(size 1 1)
					(thickness 0.15)
				)
				(justify mirror)
			)
		)
		(property "License" "Apache-2.0"
			(at 0 0 180)
			(unlocked yes)
			(layer "B.Fab")
			(hide yes)
			(effects
				(font
					(size 1 1)
					(thickness 0.15)
				)
				(justify mirror)
			)
		)
		(property "Author" "Antmicro"
			(at 0 0 180)
			(unlocked yes)
			(layer "B.Fab")
			(hide yes)
			(effects
				(font
					(size 1 1)
					(thickness 0.15)
				)
				(justify mirror)
			)
		)
		(property "Tolerance" "1%"
			(at 0 0 180)
			(unlocked yes)
			(layer "B.Fab")
			(hide yes)
			(effects
				(font
					(size 1 1)
					(thickness 0.15)
				)
				(justify mirror)
			)
		)
		(sheetname "/USB Debug, PD/")
		(sheetfile "usb_debug_pd.kicad_sch")
		(attr smd)
		(fp_rect
			(start -0.925 0.47)
			(end 0.925 -0.47)
			(stroke
				(width 0.05)
				(type default)
			)
			(fill no)
			(layer "B.CrtYd")
		)
		(fp_rect
			(start -0.5 0.25)
			(end 0.5 -0.25)
			(stroke
				(width 0.15)
				(type solid)
			)
			(fill no)
			(layer "B.Fab")
		)
		(fp_text user "License: Apache-2.0"
			(at -0.95 -5.169 0)
			(layer "B.Fab")
			(effects
				(font
					(size 0.7 0.7)
					(thickness 0.15)
				)
				(justify right top mirror)
			)
		)
		(fp_text user "${REFERENCE}"
			(at -0.95 -3.168 0)
			(layer "B.Fab")
			(effects
				(font
					(size 0.7 0.7)
					(thickness 0.15)
				)
				(justify right top mirror)
			)
		)
		(fp_text user "Author: Antmicro"
			(at -0.95 -4.169 0)
			(layer "B.Fab")
			(effects
				(font
					(size 0.7 0.7)
					(thickness 0.15)
				)
				(justify right top mirror)
			)
		)
		(pad "1" smd roundrect
			(at -0.48 0)
			(size 0.59 0.64)
			(layers "B.Cu" "B.Mask" "B.Paste")
			(roundrect_rratio 0.25)
			(net 973 "/USB Debug, PD/USB_FTDI_P")
			(pintype "passive")
		)
		(pad "2" smd roundrect
			(at 0.48 0)
			(size 0.59 0.64)
			(layers "B.Cu" "B.Mask" "B.Paste")
			(roundrect_rratio 0.25)
			(net 489 "/USB Debug, PD/USBC0_D_P")
			(pintype "passive")
		)
	)
)
